#ISCELL
  mstr_misc prelim *
  *
#ISCELL
  mstr_symbols design_note *
  *
#ISCELL
  mstr_symbols intel_corp_bpage *
  *
#ISCELL
  mstr_standard offpage *
  page27_i1
#ISCELL
  mstr_standard tap *
  page27_i10
#ISCELL
  mstr_standard tap *
  page27_i100
#ISCELL
  mstr_standard tap *
  page27_i101
#ISCELL
  mstr_standard tap *
  page27_i102
#ISCELL
  mstr_standard tap *
  page27_i103
#ISCELL
  mstr_standard tap *
  page27_i104
#ISCELL
  mstr_standard tap *
  page27_i105
#ISCELL
  mstr_standard tap *
  page27_i106
#ISCELL
  mstr_standard tap *
  page27_i107
#ISCELL
  mstr_standard tap *
  page27_i108
#ISCELL
  mstr_standard tap *
  page27_i109
#ISCELL
  mstr_standard tap *
  page27_i11
#ISCELL
  mstr_standard tap *
  page27_i110
#ISCELL
  mstr_standard tap *
  page27_i111
#ISCELL
  mstr_standard tap *
  page27_i112
#ISCELL
  mstr_standard tap *
  page27_i113
#ISCELL
  mstr_standard tap *
  page27_i114
#ISCELL
  mstr_standard tap *
  page27_i115
#ISCELL
  mstr_standard tap *
  page27_i116
#ISCELL
  mstr_standard tap *
  page27_i117
#ISCELL
  mstr_standard tap *
  page27_i118
#ISCELL
  mstr_standard tap *
  page27_i119
#ISCELL
  mstr_standard tap *
  page27_i12
#ISCELL
  mstr_standard tap *
  page27_i120
#ISCELL
  mstr_standard tap *
  page27_i121
#ISCELL
  mstr_standard tap *
  page27_i122
#ISCELL
  mstr_standard tap *
  page27_i123
#ISCELL
  mstr_standard tap *
  page27_i124
#ISCELL
  mstr_standard tap *
  page27_i125
#ISCELL
  mstr_standard tap *
  page27_i126
#ISCELL
  mstr_standard tap *
  page27_i127
#ISCELL
  mstr_standard tap *
  page27_i128
#ISCELL
  mstr_standard tap *
  page27_i129
#ISCELL
  mstr_standard tap *
  page27_i13
#ISCELL
  mstr_standard tap *
  page27_i130
#ISCELL
  mstr_standard tap *
  page27_i131
#ISCELL
  mstr_standard tap *
  page27_i132
#ISCELL
  mstr_standard tap *
  page27_i133
#ISCELL
  mstr_standard tap *
  page27_i134
#ISCELL
  mstr_standard tap *
  page27_i135
#ISCELL
  mstr_standard tap *
  page27_i136
#ISCELL
  mstr_standard tap *
  page27_i137
#ISCELL
  mstr_standard tap *
  page27_i138
#ISCELL
  mstr_standard tap *
  page27_i139
#ISCELL
  mstr_standard tap *
  page27_i14
#ISCELL
  mstr_standard tap *
  page27_i140
#ISCELL
  mstr_standard tap *
  page27_i141
#ISCELL
  mstr_standard tap *
  page27_i142
#ISCELL
  mstr_standard tap *
  page27_i143
#ISCELL
  mstr_standard tap *
  page27_i144
#ISCELL
  mstr_standard tap *
  page27_i145
#ISCELL
  mstr_standard tap *
  page27_i146
#ISCELL
  mstr_standard tap *
  page27_i147
#ISCELL
  mstr_standard offpage *
  page27_i148
#ISCELL
  mstr_standard offpage *
  page27_i149
#ISCELL
  mstr_standard tap *
  page27_i15
#ISCELL
  mstr_standard offpage *
  page27_i150
#ISCELL
  mstr_standard offpage *
  page27_i151
#ISCELL
  mstr_standard offpage *
  page27_i152
#ISCELL
  mstr_standard offpage *
  page27_i153
#ISCELL
  mstr_standard offpage *
  page27_i154
#ISCELL
  mstr_standard offpage *
  page27_i155
#ISCELL
  mstr_standard offpage *
  page27_i156
#ISCELL
  mstr_standard offpage *
  page27_i157
#ISCELL
  mstr_standard tap *
  page27_i158
#ISCELL
  mstr_standard tap *
  page27_i159
#ISCELL
  mstr_standard tap *
  page27_i16
#ISCELL
  mstr_standard tap *
  page27_i160
#ISCELL
  mstr_standard tap *
  page27_i161
#ISCELL
  mstr_standard tap *
  page27_i162
#ISCELL
  mstr_standard tap *
  page27_i163
#ISCELL
  mstr_standard tap *
  page27_i164
#ISCELL
  mstr_standard tap *
  page27_i165
#ISCELL
  mstr_standard tap *
  page27_i166
#ISCELL
  mstr_standard tap *
  page27_i167
#ISCELL
  mstr_standard tap *
  page27_i168
#ISCELL
  mstr_standard tap *
  page27_i169
#ISCELL
  mstr_standard tap *
  page27_i17
#ISCELL
  mstr_standard tap *
  page27_i170
#ISCELL
  mstr_standard offpage *
  page27_i171
#CELL
  chpset_lib skx_ext_b *
  page27_i172
#ISCELL
  mstr_standard tap *
  page27_i18
#ISCELL
  mstr_standard tap *
  page27_i19
#ISCELL
  mstr_standard offpage *
  page27_i2
#ISCELL
  mstr_standard tap *
  page27_i20
#ISCELL
  mstr_standard tap *
  page27_i21
#ISCELL
  mstr_standard tap *
  page27_i22
#ISCELL
  mstr_standard tap *
  page27_i23
#ISCELL
  mstr_standard tap *
  page27_i24
#ISCELL
  mstr_standard tap *
  page27_i25
#ISCELL
  mstr_standard tap *
  page27_i26
#ISCELL
  mstr_standard tap *
  page27_i27
#ISCELL
  mstr_standard tap *
  page27_i28
#ISCELL
  mstr_standard tap *
  page27_i29
#ISCELL
  mstr_standard offpage *
  page27_i3
#ISCELL
  mstr_standard tap *
  page27_i30
#ISCELL
  mstr_standard tap *
  page27_i32
#ISCELL
  mstr_standard tap *
  page27_i33
#ISCELL
  mstr_standard tap *
  page27_i34
#ISCELL
  mstr_standard tap *
  page27_i35
#ISCELL
  mstr_standard tap *
  page27_i36
#ISCELL
  mstr_standard tap *
  page27_i37
#ISCELL
  mstr_standard tap *
  page27_i38
#ISCELL
  mstr_standard tap *
  page27_i39
#ISCELL
  mstr_standard offpage *
  page27_i4
#ISCELL
  mstr_standard tap *
  page27_i40
#ISCELL
  mstr_standard tap *
  page27_i41
#ISCELL
  mstr_standard tap *
  page27_i42
#ISCELL
  mstr_standard tap *
  page27_i43
#ISCELL
  mstr_standard tap *
  page27_i44
#ISCELL
  mstr_standard tap *
  page27_i45
#ISCELL
  mstr_standard tap *
  page27_i46
#ISCELL
  mstr_standard tap *
  page27_i47
#ISCELL
  mstr_standard tap *
  page27_i48
#ISCELL
  mstr_standard tap *
  page27_i49
#ISCELL
  mstr_standard tap *
  page27_i5
#ISCELL
  mstr_standard tap *
  page27_i50
#ISCELL
  mstr_standard tap *
  page27_i51
#ISCELL
  mstr_standard tap *
  page27_i52
#ISCELL
  mstr_standard tap *
  page27_i53
#ISCELL
  mstr_standard tap *
  page27_i54
#ISCELL
  mstr_standard tap *
  page27_i55
#ISCELL
  mstr_standard tap *
  page27_i56
#ISCELL
  mstr_standard tap *
  page27_i57
#ISCELL
  mstr_standard tap *
  page27_i58
#ISCELL
  mstr_standard tap *
  page27_i59
#ISCELL
  mstr_standard tap *
  page27_i6
#ISCELL
  mstr_standard tap *
  page27_i60
#ISCELL
  mstr_standard tap *
  page27_i61
#ISCELL
  mstr_standard tap *
  page27_i62
#ISCELL
  mstr_standard tap *
  page27_i63
#ISCELL
  mstr_standard tap *
  page27_i64
#ISCELL
  mstr_standard tap *
  page27_i65
#ISCELL
  mstr_standard tap *
  page27_i66
#ISCELL
  mstr_standard tap *
  page27_i67
#ISCELL
  mstr_standard tap *
  page27_i68
#ISCELL
  mstr_standard tap *
  page27_i69
#ISCELL
  mstr_standard tap *
  page27_i7
#ISCELL
  mstr_standard tap *
  page27_i70
#ISCELL
  mstr_standard tap *
  page27_i71
#ISCELL
  mstr_standard tap *
  page27_i72
#ISCELL
  mstr_standard offpage *
  page27_i73
#ISCELL
  mstr_standard tap *
  page27_i74
#ISCELL
  mstr_standard tap *
  page27_i75
#ISCELL
  mstr_standard tap *
  page27_i76
#ISCELL
  mstr_standard tap *
  page27_i77
#ISCELL
  mstr_standard tap *
  page27_i78
#ISCELL
  mstr_standard tap *
  page27_i79
#ISCELL
  mstr_standard tap *
  page27_i8
#ISCELL
  mstr_standard tap *
  page27_i80
#ISCELL
  mstr_standard tap *
  page27_i81
#ISCELL
  mstr_standard tap *
  page27_i82
#ISCELL
  mstr_standard tap *
  page27_i83
#ISCELL
  mstr_standard tap *
  page27_i84
#ISCELL
  mstr_standard tap *
  page27_i85
#ISCELL
  mstr_standard tap *
  page27_i86
#ISCELL
  mstr_standard tap *
  page27_i87
#ISCELL
  mstr_standard tap *
  page27_i88
#ISCELL
  mstr_standard tap *
  page27_i89
#ISCELL
  mstr_standard tap *
  page27_i9
#ISCELL
  mstr_standard tap *
  page27_i90
#ISCELL
  mstr_standard tap *
  page27_i91
#ISCELL
  mstr_standard tap *
  page27_i92
#ISCELL
  mstr_standard tap *
  page27_i93
#ISCELL
  mstr_standard tap *
  page27_i94
#ISCELL
  mstr_standard tap *
  page27_i95
#ISCELL
  mstr_standard tap *
  page27_i96
#ISCELL
  mstr_standard tap *
  page27_i97
#ISCELL
  mstr_standard tap *
  page27_i98
#ISCELL
  mstr_standard tap *
  page27_i99
